(kicad_pcb
	(version 20241229)
	(generator "pcbnew")
	(generator_version "9.0")
	(general
		(thickness 1.599998)
		(legacy_teardrops no)
	)
	(paper "A4")
	(title_block
		(title "Artix - Datacenter Secure Control Module (DC-SCM)")
		(date "2024-11-06")
		(rev "1.1.3")
		(comment 9 "footprints 186-191 of 544")
	)
	(layers
		(0 "F.Cu" signal)
		(4 "In1.Cu" signal)
		(6 "In2.Cu" signal)
		(8 "In3.Cu" signal)
		(10 "In4.Cu" signal)
		(12 "In5.Cu" signal)
		(14 "In6.Cu" signal)
		(2 "B.Cu" signal)
		(9 "F.Adhes" user "F.Adhesive")
		(11 "B.Adhes" user "B.Adhesive")
		(13 "F.Paste" user)
		(15 "B.Paste" user)
		(5 "F.SilkS" user "F.Silkscreen")
		(7 "B.SilkS" user "B.Silkscreen")
		(1 "F.Mask" user)
		(3 "B.Mask" user)
		(17 "Dwgs.User" user "User.Drawings")
		(19 "Cmts.User" user "User.Comments")
		(21 "Eco1.User" user "User.Eco1")
		(23 "Eco2.User" user "User.Eco2")
		(25 "Edge.Cuts" user)
		(27 "Margin" user)
		(31 "F.CrtYd" user "F.Courtyard")
		(29 "B.CrtYd" user "B.Courtyard")
		(35 "F.Fab" user)
		(33 "B.Fab" user)
	)
	(footprint "antmicro-footprints:R_0402_1005Metric"
		(layer "F.Cu")
		(at 81.265 61.7)
		(descr "Resistor SMD 0402")
		(tags "resistor SMD 0402")
		(property "Reference" "R67"
			(at -2.165 -0.7 0)
			(layer "F.SilkS")
			(effects
				(font
					(size 0.7 0.7)
					(thickness 0.15)
				)
				(justify left bottom)
			)
		)
		(property "Value" "R_243k_0402"
			(at 0 1.4 0)
			(layer "F.Fab")
			(effects
				(font
					(size 0.7 0.7)
					(thickness 0.15)
				)
				(justify left bottom)
			)
		)
		(property "Datasheet" "https://www.bourns.com/docs/product-datasheets/cr.pdf"
			(at 0 0 0)
			(layer "F.Fab")
			(hide yes)
			(effects
				(font
					(size 1.27 1.27)
					(thickness 0.15)
				)
			)
		)
		(property "Description" "SMD Chip Resistor"
			(at 0 0 0)
			(layer "F.Fab")
			(hide yes)
			(effects
				(font
					(size 1.27 1.27)
					(thickness 0.15)
				)
			)
		)
		(property "Author" "Antmicro"
			(at 0 0 0)
			(layer "F.Fab")
			(hide yes)
			(effects
				(font
					(size 1 1)
					(thickness 0.15)
				)
			)
		)
		(property "License" "Apache-2.0"
			(at 0 0 0)
			(layer "F.Fab")
			(hide yes)
			(effects
				(font
					(size 1 1)
					(thickness 0.15)
				)
			)
		)
		(property "MPN" "CR0402-FX-2433GLF"
			(at 0 0 0)
			(layer "F.Fab")
			(hide yes)
			(effects
				(font
					(size 1 1)
					(thickness 0.15)
				)
			)
		)
		(property "Manufacturer" "Bourns"
			(at 0 0 0)
			(layer "F.Fab")
			(hide yes)
			(effects
				(font
					(size 1 1)
					(thickness 0.15)
				)
			)
		)
		(property "Tolerance" "1%"
			(at 0 0 0)
			(layer "F.Fab")
			(hide yes)
			(effects
				(font
					(size 1 1)
					(thickness 0.15)
				)
			)
		)
		(property "Val" "243k"
			(at 0 0 0)
			(layer "F.Fab")
			(hide yes)
			(effects
				(font
					(size 1 1)
					(thickness 0.15)
				)
			)
		)
		(sheetname "/Power supply/")
		(sheetfile "power-supply.kicad_sch")
		(attr smd)
		(fp_rect
			(start -0.925 -0.47)
			(end 0.925 0.47)
			(stroke
				(width 0.05)
				(type default)
			)
			(fill no)
			(layer "F.CrtYd")
		)
		(fp_rect
			(start -0.5 -0.25)
			(end 0.5 0.25)
			(stroke
				(width 0.15)
				(type solid)
			)
			(fill no)
			(layer "F.Fab")
		)
		(pad "1" smd roundrect
			(at -0.48 0)
			(size 0.59 0.64)
			(layers "F.Cu" "F.Mask" "F.Paste")
			(roundrect_rratio 0.25)
			(net 1 "GND")
			(pintype "passive")
		)
		(pad "2" smd roundrect
			(at 0.48 0)
			(size 0.59 0.64)
			(layers "F.Cu" "F.Mask" "F.Paste")
			(roundrect_rratio 0.25)
			(net 226 "Net-(U25-RT{slash}CLK)")
			(pintype "passive")
		)
	)
	(footprint "antmicro-footprints:R_0402_1005Metric"
		(layer "F.Cu")
		(at 75.525 62.525 180)
		(descr "Resistor SMD 0402")
		(tags "resistor SMD 0402")
		(property "Reference" "R66"
			(at -0.875 2.625 180)
			(layer "F.SilkS")
			(effects
				(font
					(size 0.7 0.7)
					(thickness 0.15)
				)
				(justify right bottom)
			)
		)
		(property "Value" "R_16k9_0402"
			(at 0 1.4 0)
			(layer "F.Fab")
			(effects
				(font
					(size 0.7 0.7)
					(thickness 0.15)
				)
				(justify right bottom)
			)
		)
		(property "Datasheet" "https://www.bourns.com/docs/product-datasheets/cr.pdf"
			(at 0 0 180)
			(layer "F.Fab")
			(hide yes)
			(effects
				(font
					(size 1.27 1.27)
					(thickness 0.15)
				)
			)
		)
		(property "Description" "SMD Chip Resistor, Ceramic, 16.9 kohm, ± 1%, 62.5 mW, 0402 [1005 Metric], Thick Film"
			(at 0 0 180)
			(layer "F.Fab")
			(hide yes)
			(effects
				(font
					(size 1.27 1.27)
					(thickness 0.15)
				)
			)
		)
		(property "Author" "Antmicro"
			(at 151.05 125.05 0)
			(layer "F.Fab")
			(hide yes)
			(effects
				(font
					(size 1 1)
					(thickness 0.15)
				)
			)
		)
		(property "License" "Apache-2.0"
			(at 151.05 125.05 0)
			(layer "F.Fab")
			(hide yes)
			(effects
				(font
					(size 1 1)
					(thickness 0.15)
				)
			)
		)
		(property "MPN" "CR0402-FX-1692GLF"
			(at 151.05 125.05 0)
			(layer "F.Fab")
			(hide yes)
			(effects
				(font
					(size 1 1)
					(thickness 0.15)
				)
			)
		)
		(property "Manufacturer" "Bourns"
			(at 151.05 125.05 0)
			(layer "F.Fab")
			(hide yes)
			(effects
				(font
					(size 1 1)
					(thickness 0.15)
				)
			)
		)
		(property "Tolerance" "1%"
			(at 151.05 125.05 0)
			(layer "F.Fab")
			(hide yes)
			(effects
				(font
					(size 1 1)
					(thickness 0.15)
				)
			)
		)
		(property "Val" "16k9"
			(at 151.05 125.05 0)
			(layer "F.Fab")
			(hide yes)
			(effects
				(font
					(size 1 1)
					(thickness 0.15)
				)
			)
		)
		(sheetname "/Power supply/")
		(sheetfile "power-supply.kicad_sch")
		(attr smd)
		(fp_rect
			(start -0.925 -0.47)
			(end 0.925 0.47)
			(stroke
				(width 0.05)
				(type default)
			)
			(fill no)
			(layer "F.CrtYd")
		)
		(fp_rect
			(start -0.5 -0.25)
			(end 0.5 0.25)
			(stroke
				(width 0.15)
				(type solid)
			)
			(fill no)
			(layer "F.Fab")
		)
		(pad "1" smd roundrect
			(at -0.48 0 180)
			(size 0.59 0.64)
			(layers "F.Cu" "F.Mask" "F.Paste")
			(roundrect_rratio 0.25)
			(net 107 "Net-(U25-COMP)")
			(pintype "passive")
		)
		(pad "2" smd roundrect
			(at 0.48 0 180)
			(size 0.59 0.64)
			(layers "F.Cu" "F.Mask" "F.Paste")
			(roundrect_rratio 0.25)
			(net 111 "Net-(C68-Pad2)")
			(pintype "passive")
		)
	)
	(footprint "antmicro-footprints:C_0402_1005Metric"
		(layer "F.Cu")
		(at 82.25 67.075)
		(descr "Capacitor SMD 0402")
		(tags "capacitor SMD 0402")
		(property "Reference" "C71"
			(at -18.84 0.075 0)
			(layer "F.SilkS")
			(effects
				(font
					(size 0.7 0.7)
					(thickness 0.15)
				)
				(justify left bottom)
			)
		)
		(property "Value" "C_100n_6V3_0402"
			(at 0 1.4 0)
			(layer "F.Fab")
			(effects
				(font
					(size 0.7 0.7)
					(thickness 0.15)
				)
				(justify left bottom)
			)
		)
		(property "Datasheet" "https://www.passivecomponent.com/wp-content/uploads/datasheet/WTC_MLCC_General_Purpose.pdf"
			(at 0 0 0)
			(layer "F.Fab")
			(hide yes)
			(effects
				(font
					(size 1.27 1.27)
					(thickness 0.15)
				)
			)
		)
		(property "Description" "SMT Multilayer Ceramic Capacitor, 0.1 µF, 6.3 V, 0402 [1005 Metric], ± 10%, X5R, Walsin MLCC"
			(at 0 0 0)
			(layer "F.Fab")
			(hide yes)
			(effects
				(font
					(size 1.27 1.27)
					(thickness 0.15)
				)
			)
		)
		(property "Author" "Antmicro"
			(at 0 0 0)
			(layer "F.Fab")
			(hide yes)
			(effects
				(font
					(size 1 1)
					(thickness 0.15)
				)
			)
		)
		(property "Dielectric" ""
			(at 0 0 0)
			(layer "F.Fab")
			(hide yes)
			(effects
				(font
					(size 1 1)
					(thickness 0.15)
				)
			)
		)
		(property "License" "Apache-2.0"
			(at 0 0 0)
			(layer "F.Fab")
			(hide yes)
			(effects
				(font
					(size 1 1)
					(thickness 0.15)
				)
			)
		)
		(property "MPN" "0402X104K6R3CT"
			(at 0 0 0)
			(layer "F.Fab")
			(hide yes)
			(effects
				(font
					(size 1 1)
					(thickness 0.15)
				)
			)
		)
		(property "Manufacturer" "Walsin"
			(at 0 0 0)
			(layer "F.Fab")
			(hide yes)
			(effects
				(font
					(size 1 1)
					(thickness 0.15)
				)
			)
		)
		(property "Public" "False"
			(at 0 0 0)
			(layer "F.Fab")
			(hide yes)
			(effects
				(font
					(size 1 1)
					(thickness 0.15)
				)
			)
		)
		(property "Val" "100n"
			(at 0 0 0)
			(layer "F.Fab")
			(hide yes)
			(effects
				(font
					(size 1 1)
					(thickness 0.15)
				)
			)
		)
		(property "Voltage" ""
			(at 0 0 0)
			(layer "F.Fab")
			(hide yes)
			(effects
				(font
					(size 1 1)
					(thickness 0.15)
				)
			)
		)
		(sheetname "/Power supply/")
		(sheetfile "power-supply.kicad_sch")
		(attr smd)
		(fp_rect
			(start -0.925 -0.47)
			(end 0.925 0.47)
			(stroke
				(width 0.05)
				(type default)
			)
			(fill no)
			(layer "F.CrtYd")
		)
		(fp_line
			(start -0.494 -0.25)
			(end 0.504 -0.25)
			(stroke
				(width 0.15)
				(type solid)
			)
			(layer "F.Fab")
		)
		(fp_line
			(start -0.494 0.248)
			(end -0.494 -0.25)
			(stroke
				(width 0.15)
				(type solid)
			)
			(layer "F.Fab")
		)
		(fp_line
			(start 0.504 -0.25)
			(end 0.504 0.248)
			(stroke
				(width 0.15)
				(type solid)
			)
			(layer "F.Fab")
		)
		(fp_line
			(start 0.504 0.248)
			(end -0.494 0.248)
			(stroke
				(width 0.15)
				(type solid)
			)
			(layer "F.Fab")
		)
		(pad "1" smd roundrect
			(at -0.48 0)
			(size 0.59 0.64)
			(layers "F.Cu" "F.Mask" "F.Paste")
			(roundrect_rratio 0.25)
			(net 110 "Net-(U25-BOOT)")
			(pintype "passive")
		)
		(pad "2" smd roundrect
			(at 0.48 0)
			(size 0.59 0.64)
			(layers "F.Cu" "F.Mask" "F.Paste")
			(roundrect_rratio 0.25)
			(net 8 "Net-(D3-C)")
			(pintype "passive")
		)
	)
	(footprint "antmicro-footprints:C_0402_1005Metric"
		(layer "F.Cu")
		(at 76.125 64.025 90)
		(descr "Capacitor SMD 0402")
		(tags "capacitor SMD 0402")
		(property "Reference" "C70"
			(at 1.825 0.175 90)
			(layer "F.SilkS")
			(effects
				(font
					(size 0.7 0.7)
					(thickness 0.15)
				)
				(justify left bottom)
			)
		)
		(property "Value" "C_47p_0402"
			(at 0 1.4 90)
			(layer "F.Fab")
			(effects
				(font
					(size 0.7 0.7)
					(thickness 0.15)
				)
				(justify left bottom)
			)
		)
		(property "Datasheet" "https://www.kemet.com/en/us/capacitors/product/C0402C470J5GACTU.html"
			(at 0 0 90)
			(layer "F.Fab")
			(hide yes)
			(effects
				(font
					(size 1.27 1.27)
					(thickness 0.15)
				)
			)
		)
		(property "Description" "SMD Multilayer Ceramic Capacitor, 47 pF, 50 V, 0402 [1005 Metric], ± 5%, C0G / NP0, C Series KEMET"
			(at 0 0 90)
			(layer "F.Fab")
			(hide yes)
			(effects
				(font
					(size 1.27 1.27)
					(thickness 0.15)
				)
			)
		)
		(property "Author" "Antmicro"
			(at 140.15 -12.1 0)
			(layer "F.Fab")
			(hide yes)
			(effects
				(font
					(size 1 1)
					(thickness 0.15)
				)
			)
		)
		(property "Dielectric" "C0G"
			(at 140.15 -12.1 0)
			(layer "F.Fab")
			(hide yes)
			(effects
				(font
					(size 1 1)
					(thickness 0.15)
				)
			)
		)
		(property "License" "Apache-2.0"
			(at 140.15 -12.1 0)
			(layer "F.Fab")
			(hide yes)
			(effects
				(font
					(size 1 1)
					(thickness 0.15)
				)
			)
		)
		(property "MPN" "C0402C470J5GACTU"
			(at 140.15 -12.1 0)
			(layer "F.Fab")
			(hide yes)
			(effects
				(font
					(size 1 1)
					(thickness 0.15)
				)
			)
		)
		(property "Manufacturer" "KEMET"
			(at 140.15 -12.1 0)
			(layer "F.Fab")
			(hide yes)
			(effects
				(font
					(size 1 1)
					(thickness 0.15)
				)
			)
		)
		(property "Val" "47p"
			(at 140.15 -12.1 0)
			(layer "F.Fab")
			(hide yes)
			(effects
				(font
					(size 1 1)
					(thickness 0.15)
				)
			)
		)
		(property "Voltage" ""
			(at 140.15 -12.1 0)
			(layer "F.Fab")
			(hide yes)
			(effects
				(font
					(size 1 1)
					(thickness 0.15)
				)
			)
		)
		(sheetname "/Power supply/")
		(sheetfile "power-supply.kicad_sch")
		(attr smd)
		(fp_rect
			(start -0.925 -0.47)
			(end 0.925 0.47)
			(stroke
				(width 0.05)
				(type default)
			)
			(fill no)
			(layer "F.CrtYd")
		)
		(fp_line
			(start 0.504 -0.25)
			(end 0.504 0.248)
			(stroke
				(width 0.15)
				(type solid)
			)
			(layer "F.Fab")
		)
		(fp_line
			(start -0.494 -0.25)
			(end 0.504 -0.25)
			(stroke
				(width 0.15)
				(type solid)
			)
			(layer "F.Fab")
		)
		(fp_line
			(start 0.504 0.248)
			(end -0.494 0.248)
			(stroke
				(width 0.15)
				(type solid)
			)
			(layer "F.Fab")
		)
		(fp_line
			(start -0.494 0.248)
			(end -0.494 -0.25)
			(stroke
				(width 0.15)
				(type solid)
			)
			(layer "F.Fab")
		)
		(pad "1" smd roundrect
			(at -0.48 0 90)
			(size 0.59 0.64)
			(layers "F.Cu" "F.Mask" "F.Paste")
			(roundrect_rratio 0.25)
			(net 1 "GND")
			(pintype "passive")
		)
		(pad "2" smd roundrect
			(at 0.48 0 90)
			(size 0.59 0.64)
			(layers "F.Cu" "F.Mask" "F.Paste")
			(roundrect_rratio 0.25)
			(net 107 "Net-(U25-COMP)")
			(pintype "passive")
		)
	)
	(footprint "antmicro-footprints:C_0402_1005Metric"
		(layer "F.Cu")
		(at 82.765 61.45 -90)
		(descr "Capacitor SMD 0402")
		(tags "capacitor SMD 0402")
		(property "Reference" "C69"
			(at -2.45 0.565 90)
			(layer "F.SilkS")
			(effects
				(font
					(size 0.7 0.7)
					(thickness 0.15)
				)
				(justify right bottom)
			)
		)
		(property "Value" "C_10n_0402"
			(at 0 1.4 90)
			(layer "F.Fab")
			(effects
				(font
					(size 0.7 0.7)
					(thickness 0.15)
				)
				(justify right bottom)
			)
		)
		(property "Datasheet" "https://www.murata.com/products/productdetail?partno=GRM155R71H103KA88%23"
			(at 0 0 270)
			(layer "F.Fab")
			(hide yes)
			(effects
				(font
					(size 1.27 1.27)
					(thickness 0.15)
				)
			)
		)
		(property "Description" "SMD Multilayer Ceramic Capacitor, 10000 pF, 50 V, 0402 [1005 Metric], ± 10%, X7R, GRM Series"
			(at 0 0 270)
			(layer "F.Fab")
			(hide yes)
			(effects
				(font
					(size 1.27 1.27)
					(thickness 0.15)
				)
			)
		)
		(property "Author" "Antmicro"
			(at 21.315 144.215 0)
			(layer "F.Fab")
			(hide yes)
			(effects
				(font
					(size 1 1)
					(thickness 0.15)
				)
			)
		)
		(property "Dielectric" "X7R"
			(at 21.315 144.215 0)
			(layer "F.Fab")
			(hide yes)
			(effects
				(font
					(size 1 1)
					(thickness 0.15)
				)
			)
		)
		(property "License" "Apache-2.0"
			(at 21.315 144.215 0)
			(layer "F.Fab")
			(hide yes)
			(effects
				(font
					(size 1 1)
					(thickness 0.15)
				)
			)
		)
		(property "MPN" "GRM155R71H103KA88D"
			(at 21.315 144.215 0)
			(layer "F.Fab")
			(hide yes)
			(effects
				(font
					(size 1 1)
					(thickness 0.15)
				)
			)
		)
		(property "Manufacturer" "Murata"
			(at 21.315 144.215 0)
			(layer "F.Fab")
			(hide yes)
			(effects
				(font
					(size 1 1)
					(thickness 0.15)
				)
			)
		)
		(property "Val" "10n"
			(at 21.315 144.215 0)
			(layer "F.Fab")
			(hide yes)
			(effects
				(font
					(size 1 1)
					(thickness 0.15)
				)
			)
		)
		(property "Voltage" "50V"
			(at 21.315 144.215 0)
			(layer "F.Fab")
			(hide yes)
			(effects
				(font
					(size 1 1)
					(thickness 0.15)
				)
			)
		)
		(sheetname "/Power supply/")
		(sheetfile "power-supply.kicad_sch")
		(attr smd)
		(fp_rect
			(start -0.925 -0.47)
			(end 0.925 0.47)
			(stroke
				(width 0.05)
				(type default)
			)
			(fill no)
			(layer "F.CrtYd")
		)
		(fp_line
			(start -0.494 0.248)
			(end -0.494 -0.25)
			(stroke
				(width 0.15)
				(type solid)
			)
			(layer "F.Fab")
		)
		(fp_line
			(start 0.504 0.248)
			(end -0.494 0.248)
			(stroke
				(width 0.15)
				(type solid)
			)
			(layer "F.Fab")
		)
		(fp_line
			(start -0.494 -0.25)
			(end 0.504 -0.25)
			(stroke
				(width 0.15)
				(type solid)
			)
			(layer "F.Fab")
		)
		(fp_line
			(start 0.504 -0.25)
			(end 0.504 0.248)
			(stroke
				(width 0.15)
				(type solid)
			)
			(layer "F.Fab")
		)
		(pad "1" smd roundrect
			(at -0.48 0 270)
			(size 0.59 0.64)
			(layers "F.Cu" "F.Mask" "F.Paste")
			(roundrect_rratio 0.25)
			(net 1 "GND")
			(pintype "passive")
		)
		(pad "2" smd roundrect
			(at 0.48 0 270)
			(size 0.59 0.64)
			(layers "F.Cu" "F.Mask" "F.Paste")
			(roundrect_rratio 0.25)
			(net 106 "Net-(U25-SS{slash}TR)")
			(pintype "passive")
		)
	)
	(footprint "antmicro-footprints:C_0402_1005Metric"
		(layer "F.Cu")
		(at 75.025 64.025 90)
		(descr "Capacitor SMD 0402")
		(tags "capacitor SMD 0402")
		(property "Reference" "C68"
			(at 1.825 0.175 90)
			(layer "F.SilkS")
			(effects
				(font
					(size 0.7 0.7)
					(thickness 0.15)
				)
				(justify left bottom)
			)
		)
		(property "Value" "C_4n7_0402"
			(at 0 1.4 90)
			(layer "F.Fab")
			(effects
				(font
					(size 0.7 0.7)
					(thickness 0.15)
				)
				(justify left bottom)
			)
		)
		(property "Datasheet" "https://product.tdk.com/en/search/capacitor/ceramic/mlcc/info?part_no=CGA2B3X7S2A472K050BB"
			(at 0 0 90)
			(layer "F.Fab")
			(hide yes)
			(effects
				(font
					(size 1.27 1.27)
					(thickness 0.15)
				)
			)
		)
		(property "Description" "SMD Multilayer Ceramic Capacitor, 4700 pF, 100 V, 0402 [1005 Metric], ± 10%, X7S, CGA"
			(at 0 0 90)
			(layer "F.Fab")
			(hide yes)
			(effects
				(font
					(size 1.27 1.27)
					(thickness 0.15)
				)
			)
		)
		(property "Author" "Antmicro"
			(at 139.05 -11 0)
			(layer "F.Fab")
			(hide yes)
			(effects
				(font
					(size 1 1)
					(thickness 0.15)
				)
			)
		)
		(property "Dielectric" ""
			(at 139.05 -11 0)
			(layer "F.Fab")
			(hide yes)
			(effects
				(font
					(size 1 1)
					(thickness 0.15)
				)
			)
		)
		(property "License" "Apache-2.0"
			(at 139.05 -11 0)
			(layer "F.Fab")
			(hide yes)
			(effects
				(font
					(size 1 1)
					(thickness 0.15)
				)
			)
		)
		(property "MPN" "CGA2B3X7S2A472K050BB"
			(at 139.05 -11 0)
			(layer "F.Fab")
			(hide yes)
			(effects
				(font
					(size 1 1)
					(thickness 0.15)
				)
			)
		)
		(property "Manufacturer" "TDK"
			(at 139.05 -11 0)
			(layer "F.Fab")
			(hide yes)
			(effects
				(font
					(size 1 1)
					(thickness 0.15)
				)
			)
		)
		(property "Val" "4n7"
			(at 139.05 -11 0)
			(layer "F.Fab")
			(hide yes)
			(effects
				(font
					(size 1 1)
					(thickness 0.15)
				)
			)
		)
		(property "Voltage" ""
			(at 139.05 -11 0)
			(layer "F.Fab")
			(hide yes)
			(effects
				(font
					(size 1 1)
					(thickness 0.15)
				)
			)
		)
		(sheetname "/Power supply/")
		(sheetfile "power-supply.kicad_sch")
		(attr smd)
		(fp_rect
			(start -0.925 -0.47)
			(end 0.925 0.47)
			(stroke
				(width 0.05)
				(type default)
			)
			(fill no)
			(layer "F.CrtYd")
		)
		(fp_line
			(start 0.504 -0.25)
			(end 0.504 0.248)
			(stroke
				(width 0.15)
				(type solid)
			)
			(layer "F.Fab")
		)
		(fp_line
			(start -0.494 -0.25)
			(end 0.504 -0.25)
			(stroke
				(width 0.15)
				(type solid)
			)
			(layer "F.Fab")
		)
		(fp_line
			(start 0.504 0.248)
			(end -0.494 0.248)
			(stroke
				(width 0.15)
				(type solid)
			)
			(layer "F.Fab")
		)
		(fp_line
			(start -0.494 0.248)
			(end -0.494 -0.25)
			(stroke
				(width 0.15)
				(type solid)
			)
			(layer "F.Fab")
		)
		(pad "1" smd roundrect
			(at -0.48 0 90)
			(size 0.59 0.64)
			(layers "F.Cu" "F.Mask" "F.Paste")
			(roundrect_rratio 0.25)
			(net 1 "GND")
			(pintype "passive")
		)
		(pad "2" smd roundrect
			(at 0.48 0 90)
			(size 0.59 0.64)
			(layers "F.Cu" "F.Mask" "F.Paste")
			(roundrect_rratio 0.25)
			(net 111 "Net-(C68-Pad2)")
			(pintype "passive")
		)
	)
)
